# BASEBOARD_FAB2 (Tioga Pass) — schematic netlist excerpt (pin names and nets, part order shuffled) for the footprints in the layout excerpt that follows; sources: Cadence DE-HDL packaged netlist, KiCad conversion of Wiwynn_Tioga_Pass_MB.brd

R4D1  RES  27.4 1% CHIP  pkg 0402  page 103 : A = CLK_100M_CPU1_BCLK1_R_DN ; B = CLK_100M_CPU1_BCLK1_DN
CT67  CAP_A  0.1UF 16V 10% X7R  pkg 0402V  page 236 : A = VR_P1V05_PCH_BIREF1 ; B = GND
C2D5  CAP_A  22.0UF 4V 20% X6S  pkg 0603V  page 228 : A = PVDDQ_KLM ; B = GND

(kicad_pcb
	(version 20260206)
	(generator "pcbnew")
	(generator_version "10.0")
	(general
		(thickness 1.6)
		(legacy_teardrops no)
	)
	(paper "A4")
	(title_block
		(title "Wiwynn_Tioga_Pass_MB.brd")
		(comment 1 "Tioga Pass / footprints 359-361 of 4770")
	)
	(layers
		(0 "F.Cu" signal "TOP")
		(4 "In1.Cu" signal "L2GND")
		(6 "In2.Cu" signal "L3")
		(8 "In3.Cu" signal "L4GND")
		(10 "In4.Cu" signal "L5")
		(12 "In5.Cu" signal "L6GND")
		(14 "In6.Cu" signal "L7VCC")
		(16 "In7.Cu" signal "L8VCC")
		(18 "In8.Cu" signal "L9GND")
		(20 "In9.Cu" signal "L10")
		(22 "In10.Cu" signal "L11GND")
		(24 "In11.Cu" signal "L12")
		(26 "In12.Cu" signal "L13GND")
		(2 "B.Cu" signal "BOTTOM")
		(9 "F.Adhes" user "F.Adhesive")
		(11 "B.Adhes" user "B.Adhesive")
		(13 "F.Paste" user "Package Geometry/Pastemask Top")
		(15 "B.Paste" user "Package Geometry/Pastemask Bottom")
		(5 "F.SilkS" user "Ref Des/Silkscreen Top")
		(7 "B.SilkS" user "Ref Des/Silkscreen Bottom")
		(1 "F.Mask" user "Board Geometry/Soldermask Top")
		(3 "B.Mask" user "Board Geometry/Soldermask Bottom")
		(17 "Dwgs.User" user "User.Drawings")
		(19 "Cmts.User" user "User.Comments")
		(21 "Eco1.User" user "User.Eco1")
		(23 "Eco2.User" user "User.Eco2")
		(25 "Edge.Cuts" user "Board Geometry/Outline")
		(27 "Margin" user)
		(31 "F.CrtYd" user "Package Geometry/Place Bound Top")
		(29 "B.CrtYd" user "Package Geometry/Place Bound Bottom")
		(35 "F.Fab" user "Ref Des/Assembly Top")
		(33 "B.Fab" user "Ref Des/Assembly Bottom")
	)
	(footprint ""
		(layer "F.Cu")
		(at 164.846 -86.868 180)
		(property "Reference" "R4D1"
			(at 0 0 180)
			(layer "F.SilkS")
			(hide yes)
			(effects
				(font
					(size 1.27 1.27)
				)
			)
		)
		(property "Value" ""
			(at 0 0 180)
			(layer "F.Fab")
			(effects
				(font
					(size 1.27 1.27)
				)
			)
		)
		(duplicate_pad_numbers_are_jumpers no)
		(fp_poly
			(pts
				(xy -0.2794 -0.1016) (xy 0.2794 -0.1016) (xy 0.2794 0.9906) (xy -0.2794 0.9906)
			)
			(stroke
				(width 0)
				(type default)
			)
			(fill no)
			(layer "F.CrtYd")
		)
		(fp_line
			(start 0.2794 0.9906)
			(end 0.2794 -0.1016)
			(stroke
				(width 0.1)
				(type default)
			)
			(layer "F.Fab")
		)
		(fp_line
			(start 0.2794 -0.1016)
			(end -0.2794 -0.1016)
			(stroke
				(width 0.1)
				(type default)
			)
			(layer "F.Fab")
		)
		(fp_line
			(start -0.2794 0.9906)
			(end 0.2794 0.9906)
			(stroke
				(width 0.1)
				(type default)
			)
			(layer "F.Fab")
		)
		(fp_line
			(start -0.2794 -0.1016)
			(end -0.2794 0.9906)
			(stroke
				(width 0.1)
				(type default)
			)
			(layer "F.Fab")
		)
		(pad "1" smd rect
			(at 0 0 180)
			(size 0.508 0.508)
			(layers "F.Cu" "F.Mask" "F.Paste")
			(net "CLK_100M_CPU1_BCLK1_R_DN")
		)
		(pad "2" smd rect
			(at 0 0.889 180)
			(size 0.508 0.508)
			(layers "F.Cu" "F.Mask" "F.Paste")
			(net "CLK_100M_CPU1_BCLK1_DN")
		)
		(zone
			(layer "F.Cu")
			(hatch none 0.5)
			(connect_pads
				(clearance 0)
			)
			(min_thickness 0.25)
			(keepout
				(tracks not_allowed)
				(vias allowed)
				(pads allowed)
				(copperpour not_allowed)
				(footprints allowed)
			)
			(placement
				(enabled no)
				(sheetname "")
			)
			(fill
				(thermal_gap 0.5)
				(thermal_bridge_width 0.5)
				(island_removal_mode 0)
			)
			(polygon
				(pts
					(xy 165.1 -87.503) (xy 164.592 -87.503) (xy 164.592 -87.122) (xy 165.1 -87.122)
				)
			)
		)
		(zone
			(layer "F.Cu")
			(hatch none 0.5)
			(connect_pads
				(clearance 0)
			)
			(min_thickness 0.25)
			(keepout
				(tracks allowed)
				(vias not_allowed)
				(pads allowed)
				(copperpour not_allowed)
				(footprints allowed)
			)
			(placement
				(enabled no)
				(sheetname "")
			)
			(fill
				(thermal_gap 0.5)
				(thermal_bridge_width 0.5)
				(island_removal_mode 0)
			)
			(polygon
				(pts
					(xy 165.1 -87.122) (xy 164.592 -87.122) (xy 164.592 -87.503) (xy 165.1 -87.503)
				)
			)
		)
	)
	(footprint ""
		(layer "F.Cu")
		(at 382.708404 -158.248858 -90)
		(property "Reference" "CT67"
			(at -0.32893 -6.0706 0)
			(unlocked yes)
			(layer "F.SilkS")
			(effects
				(font
					(size 0.7874 0.5842)
					(thickness 0.1524)
				)
				(justify left)
			)
		)
		(property "Value" ""
			(at 0 0 270)
			(layer "F.Fab")
			(effects
				(font
					(size 1.27 1.27)
				)
			)
		)
		(duplicate_pad_numbers_are_jumpers no)
		(fp_poly
			(pts
				(xy 0.3048 -0.1016) (xy 0.3048 0.9906) (xy -0.3048 0.9906) (xy -0.3048 -0.1016)
			)
			(stroke
				(width 0)
				(type default)
			)
			(fill no)
			(layer "F.CrtYd")
		)
		(fp_line
			(start -0.3048 0.9906)
			(end 0.3048 0.9906)
			(stroke
				(width 0.1)
				(type default)
			)
			(layer "F.Fab")
		)
		(fp_line
			(start 0.3048 0.9906)
			(end 0.3048 -0.1016)
			(stroke
				(width 0.1)
				(type default)
			)
			(layer "F.Fab")
		)
		(fp_line
			(start -0.3048 -0.1016)
			(end -0.3048 0.9906)
			(stroke
				(width 0.1)
				(type default)
			)
			(layer "F.Fab")
		)
		(fp_line
			(start 0.3048 -0.1016)
			(end -0.3048 -0.1016)
			(stroke
				(width 0.1)
				(type default)
			)
			(layer "F.Fab")
		)
		(pad "1" smd rect
			(at 0 0 270)
			(size 0.508 0.508)
			(layers "F.Cu" "F.Mask" "F.Paste")
			(net "VR_P1V05_PCH_BIREF1")
		)
		(pad "2" smd rect
			(at 0 0.889 270)
			(size 0.508 0.508)
			(layers "F.Cu" "F.Mask" "F.Paste")
			(net "GND")
		)
		(zone
			(layer "F.Cu")
			(hatch none 0.5)
			(connect_pads
				(clearance 0)
			)
			(min_thickness 0.25)
			(keepout
				(tracks not_allowed)
				(vias allowed)
				(pads allowed)
				(copperpour not_allowed)
				(footprints allowed)
			)
			(placement
				(enabled no)
				(sheetname "")
			)
			(fill
				(thermal_gap 0.5)
				(thermal_bridge_width 0.5)
				(island_removal_mode 0)
			)
			(polygon
				(pts
					(xy 382.073404 -158.502858) (xy 382.073404 -157.994858) (xy 382.454404 -157.994858) (xy 382.454404 -158.502858)
				)
			)
		)
		(zone
			(layer "F.Cu")
			(hatch none 0.5)
			(connect_pads
				(clearance 0)
			)
			(min_thickness 0.25)
			(keepout
				(tracks allowed)
				(vias not_allowed)
				(pads allowed)
				(copperpour not_allowed)
				(footprints allowed)
			)
			(placement
				(enabled no)
				(sheetname "")
			)
			(fill
				(thermal_gap 0.5)
				(thermal_bridge_width 0.5)
				(island_removal_mode 0)
			)
			(polygon
				(pts
					(xy 382.454404 -158.502858) (xy 382.454404 -157.994858) (xy 382.073404 -157.994858) (xy 382.073404 -158.502858)
				)
			)
		)
	)
	(footprint ""
		(layer "F.Cu")
		(at 101.013768 -84.7598)
		(property "Reference" "C2D5"
			(at 0 0 0)
			(layer "F.SilkS")
			(hide yes)
			(effects
				(font
					(size 1.27 1.27)
				)
			)
		)
		(property "Value" ""
			(at 0 0 0)
			(layer "F.Fab")
			(effects
				(font
					(size 1.27 1.27)
				)
			)
		)
		(duplicate_pad_numbers_are_jumpers no)
		(fp_poly
			(pts
				(xy -0.4953 -0.2032) (xy 0.4953 -0.2032) (xy 0.4953 1.6002) (xy -0.4953 1.6002)
			)
			(stroke
				(width 0)
				(type default)
			)
			(fill no)
			(layer "F.CrtYd")
		)
		(fp_line
			(start -0.4953 -0.2032)
			(end 0.4953 -0.2032)
			(stroke
				(width 0.1)
				(type default)
			)
			(layer "F.Fab")
		)
		(fp_line
			(start -0.4953 1.6002)
			(end -0.4953 -0.2032)
			(stroke
				(width 0.1)
				(type default)
			)
			(layer "F.Fab")
		)
		(fp_line
			(start 0.4953 -0.2032)
			(end 0.4953 1.6002)
			(stroke
				(width 0.1)
				(type default)
			)
			(layer "F.Fab")
		)
		(fp_line
			(start 0.4953 1.6002)
			(end -0.4953 1.6002)
			(stroke
				(width 0.1)
				(type default)
			)
			(layer "F.Fab")
		)
		(pad "1" smd rect
			(at 0 0)
			(size 0.762 0.889)
			(layers "F.Cu" "F.Mask" "F.Paste")
			(net "PVDDQ_KLM")
		)
		(pad "2" smd rect
			(at 0 1.397)
			(size 0.762 0.889)
			(layers "F.Cu" "F.Mask" "F.Paste")
			(net "GND")
		)
		(zone
			(layer "F.Cu")
			(hatch none 0.5)
			(connect_pads
				(clearance 0)
			)
			(min_thickness 0.25)
			(keepout
				(tracks not_allowed)
				(vias allowed)
				(pads allowed)
				(copperpour not_allowed)
				(footprints allowed)
			)
			(placement
				(enabled no)
				(sheetname "")
			)
			(fill
				(thermal_gap 0.5)
				(thermal_bridge_width 0.5)
				(island_removal_mode 0)
			)
			(polygon
				(pts
					(xy 100.632768 -84.3153) (xy 101.394768 -84.3153) (xy 101.394768 -83.8073) (xy 100.632768 -83.8073)
				)
			)
		)
	)
)
